# S9S_MB_2U (Grand Teton) — schematic netlist excerpt (pin names and nets, part order shuffled) for the footprints in the layout excerpt that follows; sources: Cadence DE-HDL packaged netlist, KiCad conversion of 03242023_DA0F0TMBIJ0_F0T_Motherboard_J_brd_V01_OCP.brd

R3078  Q_RES  130 1% CHIP  pkg 0402LF  page 252 : A = LED_FM_PCH_SLP_S3_N ; B = P3V3_AUX
R4717  Q_RES  0 5% EMPTY  pkg 0402LF  page 224 : A = FM_AC_PWR_BTN_R_N ; B = FM_AC_PWR_BTN_PLD_N

(kicad_pcb
	(version 20260206)
	(generator "pcbnew")
	(generator_version "10.0")
	(general
		(thickness 1.6)
		(legacy_teardrops no)
	)
	(paper "A4")
	(title_block
		(title "03242023_DA0F0TMBIJ0_F0T_Motherboard_J_brd_V01_OCP.brd")
		(comment 1 "Grand Teton / footprints 1720-1721 of 6105")
	)
	(layers
		(0 "F.Cu" signal "TOP")
		(4 "In1.Cu" signal "GND")
		(6 "In2.Cu" signal "IN1")
		(8 "In3.Cu" signal "GND1")
		(10 "In4.Cu" signal "IN2")
		(12 "In5.Cu" signal "GND2")
		(14 "In6.Cu" signal "IN3")
		(16 "In7.Cu" signal "GND3")
		(18 "In8.Cu" signal "VCC")
		(20 "In9.Cu" signal "VCC1")
		(22 "In10.Cu" signal "GND4")
		(24 "In11.Cu" signal "IN4")
		(26 "In12.Cu" signal "GND5")
		(28 "In13.Cu" signal "IN5")
		(30 "In14.Cu" signal "GND6")
		(32 "In15.Cu" signal "IN6")
		(34 "In16.Cu" signal "GND7")
		(2 "B.Cu" signal "BOTTOM")
		(9 "F.Adhes" user "F.Adhesive")
		(11 "B.Adhes" user "B.Adhesive")
		(13 "F.Paste" user "Package Geometry/Pastemask Top")
		(15 "B.Paste" user "Package Geometry/Pastemask Bottom")
		(5 "F.SilkS" user "Ref Des/Silkscreen Top")
		(7 "B.SilkS" user "Ref Des/Silkscreen Bottom")
		(1 "F.Mask" user "Board Geometry/Soldermask Top")
		(3 "B.Mask" user "Board Geometry/Soldermask Bottom")
		(17 "Dwgs.User" user "User.Drawings")
		(19 "Cmts.User" user "User.Comments")
		(21 "Eco1.User" user "User.Eco1")
		(23 "Eco2.User" user "User.Eco2")
		(25 "Edge.Cuts" user "Board Geometry/Outline")
		(27 "Margin" user)
		(31 "F.CrtYd" user "Package Geometry/Place Bound Top")
		(29 "B.CrtYd" user "Package Geometry/Place Bound Bottom")
		(35 "F.Fab" user "Ref Des/Assembly Top")
		(33 "B.Fab" user "Ref Des/Assembly Bottom")
	)
	(footprint ""
		(layer "F.Cu")
		(at 216.1286 -119.1514 180)
		(property "Reference" "R4717"
			(at 0 0 180)
			(layer "F.SilkS")
			(hide yes)
			(effects
				(font
					(size 1.27 1.27)
				)
			)
		)
		(property "Value" ""
			(at 0 0 180)
			(layer "F.Fab")
			(effects
				(font
					(size 1.27 1.27)
				)
			)
		)
		(duplicate_pad_numbers_are_jumpers no)
		(fp_line
			(start 0.7874 0.4064)
			(end -0.7874 0.4064)
			(stroke
				(width 0.1524)
				(type default)
			)
			(layer "F.SilkS")
		)
		(fp_line
			(start 0.7874 -0.4064)
			(end 0.7874 0.4064)
			(stroke
				(width 0.1524)
				(type default)
			)
			(layer "F.SilkS")
		)
		(fp_line
			(start -0.7874 0.4064)
			(end -0.7874 -0.4064)
			(stroke
				(width 0.1524)
				(type default)
			)
			(layer "F.SilkS")
		)
		(fp_line
			(start -0.7874 -0.4064)
			(end 0.7874 -0.4064)
			(stroke
				(width 0.1524)
				(type default)
			)
			(layer "F.SilkS")
		)
		(fp_line
			(start 0.67945 0.3048)
			(end 0.120396 0.3048)
			(stroke
				(width 0.1)
				(type default)
			)
			(layer "F.Fab")
		)
		(fp_line
			(start 0.67945 -0.3048)
			(end 0.67945 0.3048)
			(stroke
				(width 0.1)
				(type default)
			)
			(layer "F.Fab")
		)
		(fp_line
			(start 0.12065 -0.2794)
			(end 0.12065 -0.3048)
			(stroke
				(width 0.1)
				(type default)
			)
			(layer "F.Fab")
		)
		(fp_line
			(start 0.12065 -0.3048)
			(end 0.67945 -0.3048)
			(stroke
				(width 0.1)
				(type default)
			)
			(layer "F.Fab")
		)
		(fp_line
			(start 0.120396 0.3048)
			(end 0.120396 0.2794)
			(stroke
				(width 0.1)
				(type default)
			)
			(layer "F.Fab")
		)
		(fp_line
			(start 0.120396 0.2794)
			(end -0.12065 0.2794)
			(stroke
				(width 0.1)
				(type default)
			)
			(layer "F.Fab")
		)
		(fp_line
			(start -0.12065 0.3048)
			(end -0.67945 0.3048)
			(stroke
				(width 0.1)
				(type default)
			)
			(layer "F.Fab")
		)
		(fp_line
			(start -0.12065 0.2794)
			(end -0.12065 0.3048)
			(stroke
				(width 0.1)
				(type default)
			)
			(layer "F.Fab")
		)
		(fp_line
			(start -0.12065 -0.2794)
			(end 0.12065 -0.2794)
			(stroke
				(width 0.1)
				(type default)
			)
			(layer "F.Fab")
		)
		(fp_line
			(start -0.12065 -0.305054)
			(end -0.12065 -0.2794)
			(stroke
				(width 0.1)
				(type default)
			)
			(layer "F.Fab")
		)
		(fp_line
			(start -0.67945 0.3048)
			(end -0.67945 -0.305054)
			(stroke
				(width 0.1)
				(type default)
			)
			(layer "F.Fab")
		)
		(fp_line
			(start -0.67945 -0.305054)
			(end -0.12065 -0.305054)
			(stroke
				(width 0.1)
				(type default)
			)
			(layer "F.Fab")
		)
		(pad "1" smd circle
			(at -0.40005 0 180)
			(size 0 0)
			(layers "F.Cu" "F.Mask" "F.Paste")
			(net "FM_AC_PWR_BTN_R_N")
		)
		(pad "2" smd circle
			(at 0.40005 0 180)
			(size 0 0)
			(layers "F.Cu" "F.Mask" "F.Paste")
			(net "FM_AC_PWR_BTN_PLD_N")
		)
	)
	(footprint ""
		(layer "F.Cu")
		(at 96.294448 -74.767694 -90)
		(property "Reference" "R3078"
			(at 0 0 270)
			(layer "F.SilkS")
			(hide yes)
			(effects
				(font
					(size 1.27 1.27)
				)
			)
		)
		(property "Value" ""
			(at 0 0 270)
			(layer "F.Fab")
			(effects
				(font
					(size 1.27 1.27)
				)
			)
		)
		(duplicate_pad_numbers_are_jumpers no)
		(fp_line
			(start -0.7874 0.4064)
			(end -0.7874 -0.4064)
			(stroke
				(width 0.1524)
				(type default)
			)
			(layer "F.SilkS")
		)
		(fp_line
			(start 0.7874 0.4064)
			(end -0.7874 0.4064)
			(stroke
				(width 0.1524)
				(type default)
			)
			(layer "F.SilkS")
		)
		(fp_line
			(start -0.7874 -0.4064)
			(end 0.7874 -0.4064)
			(stroke
				(width 0.1524)
				(type default)
			)
			(layer "F.SilkS")
		)
		(fp_line
			(start 0.7874 -0.4064)
			(end 0.7874 0.4064)
			(stroke
				(width 0.1524)
				(type default)
			)
			(layer "F.SilkS")
		)
		(fp_line
			(start -0.67945 0.3048)
			(end -0.67945 -0.305054)
			(stroke
				(width 0.1)
				(type default)
			)
			(layer "F.Fab")
		)
		(fp_line
			(start -0.12065 0.3048)
			(end -0.67945 0.3048)
			(stroke
				(width 0.1)
				(type default)
			)
			(layer "F.Fab")
		)
		(fp_line
			(start 0.120396 0.3048)
			(end 0.120396 0.2794)
			(stroke
				(width 0.1)
				(type default)
			)
			(layer "F.Fab")
		)
		(fp_line
			(start 0.67945 0.3048)
			(end 0.120396 0.3048)
			(stroke
				(width 0.1)
				(type default)
			)
			(layer "F.Fab")
		)
		(fp_line
			(start -0.12065 0.2794)
			(end -0.12065 0.3048)
			(stroke
				(width 0.1)
				(type default)
			)
			(layer "F.Fab")
		)
		(fp_line
			(start 0.120396 0.2794)
			(end -0.12065 0.2794)
			(stroke
				(width 0.1)
				(type default)
			)
			(layer "F.Fab")
		)
		(fp_line
			(start -0.12065 -0.2794)
			(end 0.12065 -0.2794)
			(stroke
				(width 0.1)
				(type default)
			)
			(layer "F.Fab")
		)
		(fp_line
			(start 0.12065 -0.2794)
			(end 0.12065 -0.3048)
			(stroke
				(width 0.1)
				(type default)
			)
			(layer "F.Fab")
		)
		(fp_line
			(start 0.12065 -0.3048)
			(end 0.67945 -0.3048)
			(stroke
				(width 0.1)
				(type default)
			)
			(layer "F.Fab")
		)
		(fp_line
			(start 0.67945 -0.3048)
			(end 0.67945 0.3048)
			(stroke
				(width 0.1)
				(type default)
			)
			(layer "F.Fab")
		)
		(fp_line
			(start -0.67945 -0.305054)
			(end -0.12065 -0.305054)
			(stroke
				(width 0.1)
				(type default)
			)
			(layer "F.Fab")
		)
		(fp_line
			(start -0.12065 -0.305054)
			(end -0.12065 -0.2794)
			(stroke
				(width 0.1)
				(type default)
			)
			(layer "F.Fab")
		)
		(pad "1" smd circle
			(at -0.40005 0 270)
			(size 0 0)
			(layers "F.Cu" "F.Mask" "F.Paste")
			(net "LED_FM_PCH_SLP_S3_N")
		)
		(pad "2" smd circle
			(at 0.40005 0 270)
			(size 0 0)
			(layers "F.Cu" "F.Mask" "F.Paste")
			(net "P3V3_AUX")
		)
	)
)
